FILE_TYPE=LIBRARY_PARTS;
primitive '0R2J-L-GP_SMD-RG5';
  pin
    '1':
      PIN_NUMBER='(1)';
      PIN_TYPE='ANALOG';
      NO_LOAD_CHECK='Both';
      NO_IO_CHECK='Both';
      NO_ASSERT_CHECK='TRUE';
      NO_DIR_CHECK='TRUE';
      ALLOW_CONNECT='TRUE';
    '2':
      PIN_NUMBER='(2)';
      PIN_TYPE='ANALOG';
      NO_LOAD_CHECK='Both';
      NO_IO_CHECK='Both';
      NO_ASSERT_CHECK='TRUE';
      NO_DIR_CHECK='TRUE';
      ALLOW_CONNECT='TRUE';
  end_pin;
  body
    PART_NAME='0R2J-L-GP';
    BODY_NAME='0R2J-L-GP';
    PHYS_DES_PREFIX='R';
    CLASS='DISCRETE';
  end_body;
end_primitive;

END.
